(kicad_pcb
	(version 20260206)
	(generator "pcbnew")
	(generator_version "10.0")
	(general
		(thickness 1.6)
		(legacy_teardrops no)
	)
	(paper "A4")
	(title_block
		(title "01162023_DA0F0TEBIF0_F0T_Expander_BD_F_brd_V02_OCP.brd")
		(comment 1 "Grand Teton / footprints 2171-2178 of 9728")
	)
	(layers
		(0 "F.Cu" signal "TOP")
		(4 "In1.Cu" signal "GND")
		(6 "In2.Cu" signal "VCC")
		(8 "In3.Cu" signal "VCC1")
		(10 "In4.Cu" signal "GND1")
		(12 "In5.Cu" signal "IN1")
		(14 "In6.Cu" signal "GND2")
		(16 "In7.Cu" signal "IN2")
		(18 "In8.Cu" signal "GND3")
		(20 "In9.Cu" signal "IN3")
		(22 "In10.Cu" signal "GND4")
		(24 "In11.Cu" signal "IN4")
		(26 "In12.Cu" signal "GND5")
		(28 "In13.Cu" signal "IN5")
		(30 "In14.Cu" signal "GND6")
		(32 "In15.Cu" signal "IN6")
		(34 "In16.Cu" signal "GND7")
		(2 "B.Cu" signal "BOTTOM")
		(9 "F.Adhes" user "F.Adhesive")
		(11 "B.Adhes" user "B.Adhesive")
		(13 "F.Paste" user "Package Geometry/Pastemask Top")
		(15 "B.Paste" user "Package Geometry/Pastemask Bottom")
		(5 "F.SilkS" user "Ref Des/Silkscreen Top")
		(7 "B.SilkS" user "Ref Des/Silkscreen Bottom")
		(1 "F.Mask" user "Board Geometry/Soldermask Top")
		(3 "B.Mask" user "Board Geometry/Soldermask Bottom")
		(17 "Dwgs.User" user "User.Drawings")
		(19 "Cmts.User" user "User.Comments")
		(21 "Eco1.User" user "User.Eco1")
		(23 "Eco2.User" user "User.Eco2")
		(25 "Edge.Cuts" user "Board Geometry/Outline")
		(27 "Margin" user)
		(31 "F.CrtYd" user "Package Geometry/Place Bound Top")
		(29 "B.CrtYd" user "Package Geometry/Place Bound Bottom")
		(35 "F.Fab" user "Ref Des/Assembly Top")
		(33 "B.Fab" user "Ref Des/Assembly Bottom")
	)
	(footprint ""
		(layer "F.Cu")
		(at 132.951474 -124.120656 -90)
		(property "Reference" "PC476"
			(at 0 0 270)
			(layer "F.SilkS")
			(hide yes)
			(effects
				(font
					(size 1.27 1.27)
				)
			)
		)
		(property "Value" ""
			(at 0 0 270)
			(layer "F.Fab")
			(effects
				(font
					(size 1.27 1.27)
				)
			)
		)
		(duplicate_pad_numbers_are_jumpers no)
		(fp_line
			(start -0.7874 0.4064)
			(end -0.7874 -0.4064)
			(stroke
				(width 0.1524)
				(type default)
			)
			(layer "F.SilkS")
		)
		(fp_line
			(start 0.7874 0.4064)
			(end -0.7874 0.4064)
			(stroke
				(width 0.1524)
				(type default)
			)
			(layer "F.SilkS")
		)
		(fp_line
			(start -0.7874 -0.4064)
			(end 0.7874 -0.4064)
			(stroke
				(width 0.1524)
				(type default)
			)
			(layer "F.SilkS")
		)
		(fp_line
			(start 0.7874 -0.4064)
			(end 0.7874 0.4064)
			(stroke
				(width 0.1524)
				(type default)
			)
			(layer "F.SilkS")
		)
		(fp_line
			(start -0.67945 0.3048)
			(end -0.67945 -0.305054)
			(stroke
				(width 0.1)
				(type default)
			)
			(layer "F.Fab")
		)
		(fp_line
			(start -0.12065 0.3048)
			(end -0.67945 0.3048)
			(stroke
				(width 0.1)
				(type default)
			)
			(layer "F.Fab")
		)
		(fp_line
			(start 0.120396 0.3048)
			(end 0.120396 0.2794)
			(stroke
				(width 0.1)
				(type default)
			)
			(layer "F.Fab")
		)
		(fp_line
			(start 0.67945 0.3048)
			(end 0.120396 0.3048)
			(stroke
				(width 0.1)
				(type default)
			)
			(layer "F.Fab")
		)
		(fp_line
			(start -0.12065 0.2794)
			(end -0.12065 0.3048)
			(stroke
				(width 0.1)
				(type default)
			)
			(layer "F.Fab")
		)
		(fp_line
			(start 0.120396 0.2794)
			(end -0.12065 0.2794)
			(stroke
				(width 0.1)
				(type default)
			)
			(layer "F.Fab")
		)
		(fp_line
			(start -0.12065 -0.2794)
			(end 0.12065 -0.2794)
			(stroke
				(width 0.1)
				(type default)
			)
			(layer "F.Fab")
		)
		(fp_line
			(start 0.12065 -0.2794)
			(end 0.12065 -0.3048)
			(stroke
				(width 0.1)
				(type default)
			)
			(layer "F.Fab")
		)
		(fp_line
			(start 0.12065 -0.3048)
			(end 0.67945 -0.3048)
			(stroke
				(width 0.1)
				(type default)
			)
			(layer "F.Fab")
		)
		(fp_line
			(start 0.67945 -0.3048)
			(end 0.67945 0.3048)
			(stroke
				(width 0.1)
				(type default)
			)
			(layer "F.Fab")
		)
		(fp_line
			(start -0.67945 -0.305054)
			(end -0.12065 -0.305054)
			(stroke
				(width 0.1)
				(type default)
			)
			(layer "F.Fab")
		)
		(fp_line
			(start -0.12065 -0.305054)
			(end -0.12065 -0.2794)
			(stroke
				(width 0.1)
				(type default)
			)
			(layer "F.Fab")
		)
		(pad "1" smd circle
			(at -0.40005 0 270)
			(size 0 0)
			(layers "F.Cu" "F.Mask" "F.Paste")
			(net "P3V3_NIC2")
		)
		(pad "2" smd circle
			(at 0.40005 0 270)
			(size 0 0)
			(layers "F.Cu" "F.Mask" "F.Paste")
			(net "GND")
		)
	)
	(footprint ""
		(layer "F.Cu")
		(at 155.380436 -124.605542)
		(property "Reference" "C252"
			(at 0 0 0)
			(layer "F.SilkS")
			(hide yes)
			(effects
				(font
					(size 1.27 1.27)
				)
			)
		)
		(property "Value" ""
			(at 0 0 0)
			(layer "F.Fab")
			(effects
				(font
					(size 1.27 1.27)
				)
			)
		)
		(duplicate_pad_numbers_are_jumpers no)
		(fp_line
			(start -0.299974 -0.150114)
			(end 0.299974 -0.150114)
			(stroke
				(width 0.1)
				(type default)
			)
			(layer "F.Fab")
		)
		(fp_line
			(start -0.299974 0.150114)
			(end -0.299974 -0.150114)
			(stroke
				(width 0.1)
				(type default)
			)
			(layer "F.Fab")
		)
		(fp_line
			(start 0.299974 -0.150114)
			(end 0.299974 0.150114)
			(stroke
				(width 0.1)
				(type default)
			)
			(layer "F.Fab")
		)
		(fp_line
			(start 0.299974 0.150114)
			(end -0.299974 0.150114)
			(stroke
				(width 0.1)
				(type default)
			)
			(layer "F.Fab")
		)
		(pad "1" smd rect
			(at -0.2667 0)
			(size 0.3048 0.381)
			(layers "F.Cu" "F.Mask" "F.Paste")
			(net "P5E_PEX1_STN1_TX_DN<27>")
		)
		(pad "2" smd rect
			(at 0.2667 0)
			(size 0.3048 0.381)
			(layers "F.Cu" "F.Mask" "F.Paste")
			(net "P5E_PEX1_STN1_TX_C_DN<27>")
		)
	)
	(footprint ""
		(layer "F.Cu")
		(at 428.319438 -149.79015 180)
		(property "Reference" "C641"
			(at 0 0 180)
			(layer "F.SilkS")
			(hide yes)
			(effects
				(font
					(size 1.27 1.27)
				)
			)
		)
		(property "Value" ""
			(at 0 0 180)
			(layer "F.Fab")
			(effects
				(font
					(size 1.27 1.27)
				)
			)
		)
		(duplicate_pad_numbers_are_jumpers no)
		(fp_line
			(start 0.299974 0.150114)
			(end -0.299974 0.150114)
			(stroke
				(width 0.1)
				(type default)
			)
			(layer "F.Fab")
		)
		(fp_line
			(start 0.299974 -0.150114)
			(end 0.299974 0.150114)
			(stroke
				(width 0.1)
				(type default)
			)
			(layer "F.Fab")
		)
		(fp_line
			(start -0.299974 0.150114)
			(end -0.299974 -0.150114)
			(stroke
				(width 0.1)
				(type default)
			)
			(layer "F.Fab")
		)
		(fp_line
			(start -0.299974 -0.150114)
			(end 0.299974 -0.150114)
			(stroke
				(width 0.1)
				(type default)
			)
			(layer "F.Fab")
		)
		(pad "1" smd rect
			(at -0.2667 0 180)
			(size 0.3048 0.381)
			(layers "F.Cu" "F.Mask" "F.Paste")
			(net "P5E_PEX3_STN0_TX_DP<12>")
		)
		(pad "2" smd rect
			(at 0.2667 0 180)
			(size 0.3048 0.381)
			(layers "F.Cu" "F.Mask" "F.Paste")
			(net "P5E_PEX3_STN0_TX_C_DP<12>")
		)
	)
	(footprint ""
		(layer "F.Cu")
		(at 172.401992 -356.244906 90)
		(property "Reference" "C2523"
			(at 0 0 90)
			(layer "F.SilkS")
			(hide yes)
			(effects
				(font
					(size 1.27 1.27)
				)
			)
		)
		(property "Value" ""
			(at 0 0 90)
			(layer "F.Fab")
			(effects
				(font
					(size 1.27 1.27)
				)
			)
		)
		(duplicate_pad_numbers_are_jumpers no)
		(fp_line
			(start 0.299974 -0.150114)
			(end 0.299974 0.150114)
			(stroke
				(width 0.1)
				(type default)
			)
			(layer "F.Fab")
		)
		(fp_line
			(start -0.299974 -0.150114)
			(end 0.299974 -0.150114)
			(stroke
				(width 0.1)
				(type default)
			)
			(layer "F.Fab")
		)
		(fp_line
			(start 0.299974 0.150114)
			(end -0.299974 0.150114)
			(stroke
				(width 0.1)
				(type default)
			)
			(layer "F.Fab")
		)
		(fp_line
			(start -0.299974 0.150114)
			(end -0.299974 -0.150114)
			(stroke
				(width 0.1)
				(type default)
			)
			(layer "F.Fab")
		)
		(pad "1" smd rect
			(at -0.2667 0 90)
			(size 0.3048 0.381)
			(layers "F.Cu" "F.Mask" "F.Paste")
			(net "P5E_PEX1_STN4_TX_DN<74>")
		)
		(pad "2" smd rect
			(at 0.2667 0 90)
			(size 0.3048 0.381)
			(layers "F.Cu" "F.Mask" "F.Paste")
			(net "P5E_PEX1_STN4_TX_C_DN<74>")
		)
	)
	(footprint ""
		(layer "F.Cu")
		(at 22.271736 -152.71115 90)
		(property "Reference" "R681"
			(at 0 0 90)
			(layer "F.SilkS")
			(hide yes)
			(effects
				(font
					(size 1.27 1.27)
				)
			)
		)
		(property "Value" ""
			(at 0 0 90)
			(layer "F.Fab")
			(effects
				(font
					(size 1.27 1.27)
				)
			)
		)
		(duplicate_pad_numbers_are_jumpers no)
		(fp_line
			(start 0.7874 -0.4064)
			(end 0.7874 0.4064)
			(stroke
				(width 0.1524)
				(type default)
			)
			(layer "F.SilkS")
		)
		(fp_line
			(start -0.7874 -0.4064)
			(end 0.7874 -0.4064)
			(stroke
				(width 0.1524)
				(type default)
			)
			(layer "F.SilkS")
		)
		(fp_line
			(start 0.7874 0.4064)
			(end -0.7874 0.4064)
			(stroke
				(width 0.1524)
				(type default)
			)
			(layer "F.SilkS")
		)
		(fp_line
			(start -0.7874 0.4064)
			(end -0.7874 -0.4064)
			(stroke
				(width 0.1524)
				(type default)
			)
			(layer "F.SilkS")
		)
		(fp_line
			(start -0.12065 -0.305054)
			(end -0.12065 -0.2794)
			(stroke
				(width 0.1)
				(type default)
			)
			(layer "F.Fab")
		)
		(fp_line
			(start -0.67945 -0.305054)
			(end -0.12065 -0.305054)
			(stroke
				(width 0.1)
				(type default)
			)
			(layer "F.Fab")
		)
		(fp_line
			(start 0.67945 -0.3048)
			(end 0.67945 0.3048)
			(stroke
				(width 0.1)
				(type default)
			)
			(layer "F.Fab")
		)
		(fp_line
			(start 0.12065 -0.3048)
			(end 0.67945 -0.3048)
			(stroke
				(width 0.1)
				(type default)
			)
			(layer "F.Fab")
		)
		(fp_line
			(start 0.12065 -0.2794)
			(end 0.12065 -0.3048)
			(stroke
				(width 0.1)
				(type default)
			)
			(layer "F.Fab")
		)
		(fp_line
			(start -0.12065 -0.2794)
			(end 0.12065 -0.2794)
			(stroke
				(width 0.1)
				(type default)
			)
			(layer "F.Fab")
		)
		(fp_line
			(start 0.120396 0.2794)
			(end -0.12065 0.2794)
			(stroke
				(width 0.1)
				(type default)
			)
			(layer "F.Fab")
		)
		(fp_line
			(start -0.12065 0.2794)
			(end -0.12065 0.3048)
			(stroke
				(width 0.1)
				(type default)
			)
			(layer "F.Fab")
		)
		(fp_line
			(start 0.67945 0.3048)
			(end 0.120396 0.3048)
			(stroke
				(width 0.1)
				(type default)
			)
			(layer "F.Fab")
		)
		(fp_line
			(start 0.120396 0.3048)
			(end 0.120396 0.2794)
			(stroke
				(width 0.1)
				(type default)
			)
			(layer "F.Fab")
		)
		(fp_line
			(start -0.12065 0.3048)
			(end -0.67945 0.3048)
			(stroke
				(width 0.1)
				(type default)
			)
			(layer "F.Fab")
		)
		(fp_line
			(start -0.67945 0.3048)
			(end -0.67945 -0.305054)
			(stroke
				(width 0.1)
				(type default)
			)
			(layer "F.Fab")
		)
		(pad "1" smd circle
			(at -0.40005 0 90)
			(size 0 0)
			(layers "F.Cu" "F.Mask" "F.Paste")
			(net "NIC0_ADC_A1")
		)
		(pad "2" smd circle
			(at 0.40005 0 90)
			(size 0 0)
			(layers "F.Cu" "F.Mask" "F.Paste")
			(net "P3V3_AUX")
		)
	)
	(footprint ""
		(layer "F.Cu")
		(at 268.53515 -84.266024 180)
		(property "Reference" "R1071"
			(at 0 0 180)
			(layer "F.SilkS")
			(hide yes)
			(effects
				(font
					(size 1.27 1.27)
				)
			)
		)
		(property "Value" ""
			(at 0 0 180)
			(layer "F.Fab")
			(effects
				(font
					(size 1.27 1.27)
				)
			)
		)
		(duplicate_pad_numbers_are_jumpers no)
		(fp_line
			(start 0.7874 0.4064)
			(end -0.7874 0.4064)
			(stroke
				(width 0.1524)
				(type default)
			)
			(layer "F.SilkS")
		)
		(fp_line
			(start 0.67945 0.3048)
			(end 0.120396 0.3048)
			(stroke
				(width 0.1)
				(type default)
			)
			(layer "F.Fab")
		)
		(fp_line
			(start 0.67945 -0.3048)
			(end 0.67945 0.3048)
			(stroke
				(width 0.1)
				(type default)
			)
			(layer "F.Fab")
		)
		(fp_line
			(start 0.12065 -0.2794)
			(end 0.12065 -0.3048)
			(stroke
				(width 0.1)
				(type default)
			)
			(layer "F.Fab")
		)
		(fp_line
			(start 0.12065 -0.3048)
			(end 0.67945 -0.3048)
			(stroke
				(width 0.1)
				(type default)
			)
			(layer "F.Fab")
		)
		(fp_line
			(start 0.120396 0.3048)
			(end 0.120396 0.2794)
			(stroke
				(width 0.1)
				(type default)
			)
			(layer "F.Fab")
		)
		(fp_line
			(start 0.120396 0.2794)
			(end -0.12065 0.2794)
			(stroke
				(width 0.1)
				(type default)
			)
			(layer "F.Fab")
		)
		(fp_line
			(start -0.12065 0.3048)
			(end -0.67945 0.3048)
			(stroke
				(width 0.1)
				(type default)
			)
			(layer "F.Fab")
		)
		(fp_line
			(start -0.12065 0.2794)
			(end -0.12065 0.3048)
			(stroke
				(width 0.1)
				(type default)
			)
			(layer "F.Fab")
		)
		(fp_line
			(start -0.12065 -0.2794)
			(end 0.12065 -0.2794)
			(stroke
				(width 0.1)
				(type default)
			)
			(layer "F.Fab")
		)
		(fp_line
			(start -0.12065 -0.305054)
			(end -0.12065 -0.2794)
			(stroke
				(width 0.1)
				(type default)
			)
			(layer "F.Fab")
		)
		(fp_line
			(start -0.67945 0.3048)
			(end -0.67945 -0.305054)
			(stroke
				(width 0.1)
				(type default)
			)
			(layer "F.Fab")
		)
		(fp_line
			(start -0.67945 -0.305054)
			(end -0.12065 -0.305054)
			(stroke
				(width 0.1)
				(type default)
			)
			(layer "F.Fab")
		)
		(pad "1" smd circle
			(at -0.40005 0 180)
			(size 0 0)
			(layers "F.Cu" "F.Mask" "F.Paste")
			(net "CLK_100M_CK440Q_0_DB2000QL_R_DP")
		)
		(pad "2" smd circle
			(at 0.40005 0 180)
			(size 0 0)
			(layers "F.Cu" "F.Mask" "F.Paste")
			(net "CLK_100M_CK440Q_0_DB2000QL_DP")
		)
	)
	(footprint ""
		(layer "F.Cu")
		(at 264.319004 -59.574684 90)
		(property "Reference" "PC552"
			(at 0 0 90)
			(layer "F.SilkS")
			(hide yes)
			(effects
				(font
					(size 1.27 1.27)
				)
			)
		)
		(property "Value" ""
			(at 0 0 90)
			(layer "F.Fab")
			(effects
				(font
					(size 1.27 1.27)
				)
			)
		)
		(duplicate_pad_numbers_are_jumpers no)
		(fp_line
			(start 0.7874 -0.4064)
			(end 0.7874 0.4064)
			(stroke
				(width 0.1524)
				(type default)
			)
			(layer "F.SilkS")
		)
		(fp_line
			(start -0.7874 -0.4064)
			(end 0.7874 -0.4064)
			(stroke
				(width 0.1524)
				(type default)
			)
			(layer "F.SilkS")
		)
		(fp_line
			(start 0.7874 0.4064)
			(end -0.7874 0.4064)
			(stroke
				(width 0.1524)
				(type default)
			)
			(layer "F.SilkS")
		)
		(fp_line
			(start -0.7874 0.4064)
			(end -0.7874 -0.4064)
			(stroke
				(width 0.1524)
				(type default)
			)
			(layer "F.SilkS")
		)
		(fp_line
			(start -0.12065 -0.305054)
			(end -0.12065 -0.2794)
			(stroke
				(width 0.1)
				(type default)
			)
			(layer "F.Fab")
		)
		(fp_line
			(start -0.67945 -0.305054)
			(end -0.12065 -0.305054)
			(stroke
				(width 0.1)
				(type default)
			)
			(layer "F.Fab")
		)
		(fp_line
			(start 0.67945 -0.3048)
			(end 0.67945 0.3048)
			(stroke
				(width 0.1)
				(type default)
			)
			(layer "F.Fab")
		)
		(fp_line
			(start 0.12065 -0.3048)
			(end 0.67945 -0.3048)
			(stroke
				(width 0.1)
				(type default)
			)
			(layer "F.Fab")
		)
		(fp_line
			(start 0.12065 -0.2794)
			(end 0.12065 -0.3048)
			(stroke
				(width 0.1)
				(type default)
			)
			(layer "F.Fab")
		)
		(fp_line
			(start -0.12065 -0.2794)
			(end 0.12065 -0.2794)
			(stroke
				(width 0.1)
				(type default)
			)
			(layer "F.Fab")
		)
		(fp_line
			(start 0.120396 0.2794)
			(end -0.12065 0.2794)
			(stroke
				(width 0.1)
				(type default)
			)
			(layer "F.Fab")
		)
		(fp_line
			(start -0.12065 0.2794)
			(end -0.12065 0.3048)
			(stroke
				(width 0.1)
				(type default)
			)
			(layer "F.Fab")
		)
		(fp_line
			(start 0.67945 0.3048)
			(end 0.120396 0.3048)
			(stroke
				(width 0.1)
				(type default)
			)
			(layer "F.Fab")
		)
		(fp_line
			(start 0.120396 0.3048)
			(end 0.120396 0.2794)
			(stroke
				(width 0.1)
				(type default)
			)
			(layer "F.Fab")
		)
		(fp_line
			(start -0.12065 0.3048)
			(end -0.67945 0.3048)
			(stroke
				(width 0.1)
				(type default)
			)
			(layer "F.Fab")
		)
		(fp_line
			(start -0.67945 0.3048)
			(end -0.67945 -0.305054)
			(stroke
				(width 0.1)
				(type default)
			)
			(layer "F.Fab")
		)
		(pad "1" smd circle
			(at -0.40005 0 90)
			(size 0 0)
			(layers "F.Cu" "F.Mask" "F.Paste")
			(net "P5V_AUX")
		)
		(pad "2" smd circle
			(at 0.40005 0 90)
			(size 0 0)
			(layers "F.Cu" "F.Mask" "F.Paste")
			(net "GND")
		)
	)
	(footprint ""
		(layer "F.Cu")
		(at 258.810506 -18.61439 90)
		(property "Reference" "U134"
			(at -1.39319 2.251964 90)
			(unlocked yes)
			(layer "F.SilkS")
			(effects
				(font
					(size 0.7874 0.5842)
					(thickness 0.1524)
				)
				(justify left)
			)
		)
		(property "Value" ""
			(at 0 0 90)
			(layer "F.Fab")
			(effects
				(font
					(size 1.27 1.27)
				)
			)
		)
		(duplicate_pad_numbers_are_jumpers no)
		(fp_line
			(start 1.463548 -1.549908)
			(end 1.463548 1.549908)
			(stroke
				(width 0.1524)
				(type default)
			)
			(layer "F.SilkS")
		)
		(fp_line
			(start 0.762 -1.549908)
			(end 1.463548 -1.549908)
			(stroke
				(width 0.1524)
				(type default)
			)
			(layer "F.SilkS")
		)
		(fp_line
			(start -0.787908 -1.549908)
			(end 0 -0.762)
			(stroke
				(width 0.1524)
				(type default)
			)
			(layer "F.SilkS")
		)
		(fp_line
			(start -1.463548 -1.549908)
			(end -0.787908 -1.549908)
			(stroke
				(width 0.1524)
				(type default)
			)
			(layer "F.SilkS")
		)
		(fp_line
			(start 0 -0.762)
			(end 0.762 -1.549908)
			(stroke
				(width 0.1524)
				(type default)
			)
			(layer "F.SilkS")
		)
		(fp_line
			(start 1.463548 1.549908)
			(end -1.463548 1.549908)
			(stroke
				(width 0.1524)
				(type default)
			)
			(layer "F.SilkS")
		)
		(fp_line
			(start -1.463548 1.549908)
			(end -1.463548 -1.549908)
			(stroke
				(width 0.1524)
				(type default)
			)
			(layer "F.SilkS")
		)
		(fp_poly
			(pts
				(xy -3.11023 -2.04978) (xy -2.891282 -1.392428) (xy -3.548634 -1.61163)
			)
			(stroke
				(width 0)
				(type default)
			)
			(fill yes)
			(layer "F.SilkS")
		)
		(fp_line
			(start 1.549908 -1.549908)
			(end 1.549908 1.549908)
			(stroke
				(width 0.1)
				(type default)
			)
			(layer "F.Fab")
		)
		(fp_line
			(start -1.549908 -1.549908)
			(end 1.549908 -1.549908)
			(stroke
				(width 0.1)
				(type default)
			)
			(layer "F.Fab")
		)
		(fp_line
			(start 1.549908 1.549908)
			(end -1.549908 1.549908)
			(stroke
				(width 0.1)
				(type default)
			)
			(layer "F.Fab")
		)
		(fp_line
			(start -1.549908 1.549908)
			(end -1.549908 -1.549908)
			(stroke
				(width 0.1)
				(type default)
			)
			(layer "F.Fab")
		)
		(fp_poly
			(pts
				(xy -3.4798 -1.359916) (xy -2.86004 -1.050036) (xy -3.4798 -0.740156)
			)
			(stroke
				(width 0)
				(type default)
			)
			(fill yes)
			(layer "F.Fab")
		)
		(pad "1" smd rect
			(at -2.175002 -1.050036 180)
			(size 0.6096 1.1684)
			(layers "F.Cu" "F.Mask" "F.Paste")
			(net "P3V3_SSD8")
		)
		(pad "2" smd rect
			(at -2.175002 -0.32512 180)
			(size 0.4318 1.1684)
			(layers "F.Cu" "F.Mask" "F.Paste")
			(net "SMB_ISO_SSD8_SCL")
		)
		(pad "3" smd rect
			(at -2.175002 0.32512 180)
			(size 0.4318 1.1684)
			(layers "F.Cu" "F.Mask" "F.Paste")
			(net "SMB_ISO_SSD8_SDA")
		)
		(pad "4" smd rect
			(at -2.175002 1.050036 180)
			(size 0.6096 1.1684)
			(layers "F.Cu" "F.Mask" "F.Paste")
			(net "GND")
		)
		(pad "5" smd rect
			(at 2.175002 1.050036 180)
			(size 0.6096 1.1684)
			(layers "F.Cu" "F.Mask" "F.Paste")
			(net "SMB_SSD8_ISO_EN")
		)
		(pad "6" smd rect
			(at 2.175002 0.32512 180)
			(size 0.4318 1.1684)
			(layers "F.Cu" "F.Mask" "F.Paste")
			(net "SMB_BIC_I2C9_MUX1_SSD8_R_SDA")
		)
		(pad "7" smd rect
			(at 2.175002 -0.32512 180)
			(size 0.4318 1.1684)
			(layers "F.Cu" "F.Mask" "F.Paste")
			(net "SMB_BIC_I2C9_MUX1_SSD8_R_SCL")
		)
		(pad "8" smd rect
			(at 2.175002 -1.050036 180)
			(size 0.6096 1.1684)
			(layers "F.Cu" "F.Mask" "F.Paste")
			(net "P3V3_AUX")
		)
	)
)
